# T6G (Grand Teton) — schematic netlist excerpt (pin names and nets, part order shuffled) for the footprints in the layout excerpt that follows; sources: Cadence DE-HDL packaged netlist, KiCad conversion of 04192023_DAF0TMB3IC0_F0TG_MB_C_brd_V02_OCP.brd

C2639  Q_CAP  22UF 4V 20% X6S  pkg C0402  page 70 : A = PVDD11_S3_P0 ; B = GND
R4150  Q_RES  33.2 1% CHIP  pkg 0402LF  page 151 : A = SMB_1_PLD_3V3AUX_SDA ; B = SMB_1_PLD_3V3AUX_SDA_R1

(kicad_pcb
	(version 20260206)
	(generator "pcbnew")
	(generator_version "10.0")
	(general
		(thickness 1.6)
		(legacy_teardrops no)
	)
	(paper "A4")
	(title_block
		(title "04192023_DAF0TMB3IC0_F0TG_MB_C_brd_V02_OCP.brd")
		(comment 1 "Grand Teton / footprints 5741-5742 of 8354")
	)
	(layers
		(0 "F.Cu" signal "TOP")
		(4 "In1.Cu" signal "GND")
		(6 "In2.Cu" signal "IN1")
		(8 "In3.Cu" signal "GND1")
		(10 "In4.Cu" signal "IN2")
		(12 "In5.Cu" signal "GND2")
		(14 "In6.Cu" signal "IN3")
		(16 "In7.Cu" signal "GND3")
		(18 "In8.Cu" signal "VCC")
		(20 "In9.Cu" signal "VCC1")
		(22 "In10.Cu" signal "GND4")
		(24 "In11.Cu" signal "IN4")
		(26 "In12.Cu" signal "GND5")
		(28 "In13.Cu" signal "IN5")
		(30 "In14.Cu" signal "GND6")
		(32 "In15.Cu" signal "IN6")
		(34 "In16.Cu" signal "GND7")
		(2 "B.Cu" signal "BOTTOM")
		(9 "F.Adhes" user "F.Adhesive")
		(11 "B.Adhes" user "B.Adhesive")
		(13 "F.Paste" user "Package Geometry/Pastemask Top")
		(15 "B.Paste" user "Package Geometry/Pastemask Bottom")
		(5 "F.SilkS" user "Ref Des/Silkscreen Top")
		(7 "B.SilkS" user "Ref Des/Silkscreen Bottom")
		(1 "F.Mask" user "Board Geometry/Soldermask Top")
		(3 "B.Mask" user "Board Geometry/Soldermask Bottom")
		(17 "Dwgs.User" user "User.Drawings")
		(19 "Cmts.User" user "User.Comments")
		(21 "Eco1.User" user "User.Eco1")
		(23 "Eco2.User" user "User.Eco2")
		(25 "Edge.Cuts" user "Board Geometry/Outline")
		(27 "Margin" user)
		(31 "F.CrtYd" user "Package Geometry/Place Bound Top")
		(29 "B.CrtYd" user "Package Geometry/Place Bound Bottom")
		(35 "F.Fab" user "Ref Des/Assembly Top")
		(33 "B.Fab" user "Ref Des/Assembly Bottom")
	)
	(footprint ""
		(layer "B.Cu")
		(at 373.202454 -266.00531)
		(property "Reference" "C2639"
			(at 0 0 0)
			(layer "B.SilkS")
			(hide yes)
			(effects
				(font
					(size 1.27 1.27)
				)
				(justify mirror)
			)
		)
		(property "Value" ""
			(at 0 0 0)
			(layer "B.Fab")
			(effects
				(font
					(size 1.27 1.27)
				)
				(justify mirror)
			)
		)
		(duplicate_pad_numbers_are_jumpers no)
		(fp_line
			(start -0.7874 -0.4064)
			(end -0.7874 0.4064)
			(stroke
				(width 0.1524)
				(type default)
			)
			(layer "B.SilkS")
		)
		(fp_line
			(start -0.7874 0.4064)
			(end 0.7874 0.4064)
			(stroke
				(width 0.1524)
				(type default)
			)
			(layer "B.SilkS")
		)
		(fp_line
			(start 0.7874 -0.4064)
			(end -0.7874 -0.4064)
			(stroke
				(width 0.1524)
				(type default)
			)
			(layer "B.SilkS")
		)
		(fp_line
			(start 0.7874 0.4064)
			(end 0.7874 -0.4064)
			(stroke
				(width 0.1524)
				(type default)
			)
			(layer "B.SilkS")
		)
		(fp_line
			(start -0.67945 -0.3048)
			(end -0.67945 0.3048)
			(stroke
				(width 0.1)
				(type default)
			)
			(layer "B.Fab")
		)
		(fp_line
			(start -0.67945 0.3048)
			(end -0.120396 0.3048)
			(stroke
				(width 0.1)
				(type default)
			)
			(layer "B.Fab")
		)
		(fp_line
			(start -0.12065 -0.3048)
			(end -0.67945 -0.3048)
			(stroke
				(width 0.1)
				(type default)
			)
			(layer "B.Fab")
		)
		(fp_line
			(start -0.12065 -0.2794)
			(end -0.12065 -0.3048)
			(stroke
				(width 0.1)
				(type default)
			)
			(layer "B.Fab")
		)
		(fp_line
			(start -0.120396 0.2794)
			(end 0.12065 0.2794)
			(stroke
				(width 0.1)
				(type default)
			)
			(layer "B.Fab")
		)
		(fp_line
			(start -0.120396 0.3048)
			(end -0.120396 0.2794)
			(stroke
				(width 0.1)
				(type default)
			)
			(layer "B.Fab")
		)
		(fp_line
			(start 0.12065 -0.305054)
			(end 0.12065 -0.2794)
			(stroke
				(width 0.1)
				(type default)
			)
			(layer "B.Fab")
		)
		(fp_line
			(start 0.12065 -0.2794)
			(end -0.12065 -0.2794)
			(stroke
				(width 0.1)
				(type default)
			)
			(layer "B.Fab")
		)
		(fp_line
			(start 0.12065 0.2794)
			(end 0.12065 0.3048)
			(stroke
				(width 0.1)
				(type default)
			)
			(layer "B.Fab")
		)
		(fp_line
			(start 0.12065 0.3048)
			(end 0.67945 0.3048)
			(stroke
				(width 0.1)
				(type default)
			)
			(layer "B.Fab")
		)
		(fp_line
			(start 0.67945 -0.305054)
			(end 0.12065 -0.305054)
			(stroke
				(width 0.1)
				(type default)
			)
			(layer "B.Fab")
		)
		(fp_line
			(start 0.67945 0.3048)
			(end 0.67945 -0.305054)
			(stroke
				(width 0.1)
				(type default)
			)
			(layer "B.Fab")
		)
		(pad "1" smd circle
			(at 0.40005 0 180)
			(size 0 0)
			(layers "B.Cu" "B.Mask" "B.Paste")
			(net "PVDD11_S3_P0")
		)
		(pad "2" smd circle
			(at -0.40005 0 180)
			(size 0 0)
			(layers "B.Cu" "B.Mask" "B.Paste")
			(net "GND")
		)
	)
	(footprint ""
		(layer "B.Cu")
		(at 160.69183 -17.79016)
		(property "Reference" "R4150"
			(at 0 0 0)
			(layer "B.SilkS")
			(hide yes)
			(effects
				(font
					(size 1.27 1.27)
				)
				(justify mirror)
			)
		)
		(property "Value" ""
			(at 0 0 0)
			(layer "B.Fab")
			(effects
				(font
					(size 1.27 1.27)
				)
				(justify mirror)
			)
		)
		(duplicate_pad_numbers_are_jumpers no)
		(fp_line
			(start -0.7874 -0.4064)
			(end -0.7874 0.4064)
			(stroke
				(width 0.1524)
				(type default)
			)
			(layer "B.SilkS")
		)
		(fp_line
			(start -0.7874 0.4064)
			(end 0.7874 0.4064)
			(stroke
				(width 0.1524)
				(type default)
			)
			(layer "B.SilkS")
		)
		(fp_line
			(start 0.7874 -0.4064)
			(end -0.7874 -0.4064)
			(stroke
				(width 0.1524)
				(type default)
			)
			(layer "B.SilkS")
		)
		(fp_line
			(start 0.7874 0.4064)
			(end 0.7874 -0.4064)
			(stroke
				(width 0.1524)
				(type default)
			)
			(layer "B.SilkS")
		)
		(fp_line
			(start -0.67945 -0.3048)
			(end -0.67945 0.3048)
			(stroke
				(width 0.1)
				(type default)
			)
			(layer "B.Fab")
		)
		(fp_line
			(start -0.67945 0.3048)
			(end -0.120396 0.3048)
			(stroke
				(width 0.1)
				(type default)
			)
			(layer "B.Fab")
		)
		(fp_line
			(start -0.12065 -0.3048)
			(end -0.67945 -0.3048)
			(stroke
				(width 0.1)
				(type default)
			)
			(layer "B.Fab")
		)
		(fp_line
			(start -0.12065 -0.2794)
			(end -0.12065 -0.3048)
			(stroke
				(width 0.1)
				(type default)
			)
			(layer "B.Fab")
		)
		(fp_line
			(start -0.120396 0.2794)
			(end 0.12065 0.2794)
			(stroke
				(width 0.1)
				(type default)
			)
			(layer "B.Fab")
		)
		(fp_line
			(start -0.120396 0.3048)
			(end -0.120396 0.2794)
			(stroke
				(width 0.1)
				(type default)
			)
			(layer "B.Fab")
		)
		(fp_line
			(start 0.12065 -0.305054)
			(end 0.12065 -0.2794)
			(stroke
				(width 0.1)
				(type default)
			)
			(layer "B.Fab")
		)
		(fp_line
			(start 0.12065 -0.2794)
			(end -0.12065 -0.2794)
			(stroke
				(width 0.1)
				(type default)
			)
			(layer "B.Fab")
		)
		(fp_line
			(start 0.12065 0.2794)
			(end 0.12065 0.3048)
			(stroke
				(width 0.1)
				(type default)
			)
			(layer "B.Fab")
		)
		(fp_line
			(start 0.12065 0.3048)
			(end 0.67945 0.3048)
			(stroke
				(width 0.1)
				(type default)
			)
			(layer "B.Fab")
		)
		(fp_line
			(start 0.67945 -0.305054)
			(end 0.12065 -0.305054)
			(stroke
				(width 0.1)
				(type default)
			)
			(layer "B.Fab")
		)
		(fp_line
			(start 0.67945 0.3048)
			(end 0.67945 -0.305054)
			(stroke
				(width 0.1)
				(type default)
			)
			(layer "B.Fab")
		)
		(pad "1" smd circle
			(at 0.40005 0 180)
			(size 0 0)
			(layers "B.Cu" "B.Mask" "B.Paste")
			(net "SMB_1_PLD_3V3AUX_SDA")
		)
		(pad "2" smd circle
			(at -0.40005 0 180)
			(size 0 0)
			(layers "B.Cu" "B.Mask" "B.Paste")
			(net "SMB_1_PLD_3V3AUX_SDA_R1")
		)
	)
)
